(kicad_pcb
	(version 20260206)
	(generator "pcbnew")
	(generator_version "10.0")
	(general
		(thickness 1.6)
		(legacy_teardrops no)
	)
	(paper "A4")
	(title_block
		(title "03242023_DA0F0TMBIJ0_F0T_Motherboard_J_brd_V01_OCP.brd")
		(comment 1 "Grand Teton / footprints 230-235 of 6105")
	)
	(layers
		(0 "F.Cu" signal "TOP")
		(4 "In1.Cu" signal "GND")
		(6 "In2.Cu" signal "IN1")
		(8 "In3.Cu" signal "GND1")
		(10 "In4.Cu" signal "IN2")
		(12 "In5.Cu" signal "GND2")
		(14 "In6.Cu" signal "IN3")
		(16 "In7.Cu" signal "GND3")
		(18 "In8.Cu" signal "VCC")
		(20 "In9.Cu" signal "VCC1")
		(22 "In10.Cu" signal "GND4")
		(24 "In11.Cu" signal "IN4")
		(26 "In12.Cu" signal "GND5")
		(28 "In13.Cu" signal "IN5")
		(30 "In14.Cu" signal "GND6")
		(32 "In15.Cu" signal "IN6")
		(34 "In16.Cu" signal "GND7")
		(2 "B.Cu" signal "BOTTOM")
		(9 "F.Adhes" user "F.Adhesive")
		(11 "B.Adhes" user "B.Adhesive")
		(13 "F.Paste" user "Package Geometry/Pastemask Top")
		(15 "B.Paste" user "Package Geometry/Pastemask Bottom")
		(5 "F.SilkS" user "Ref Des/Silkscreen Top")
		(7 "B.SilkS" user "Ref Des/Silkscreen Bottom")
		(1 "F.Mask" user "Board Geometry/Soldermask Top")
		(3 "B.Mask" user "Board Geometry/Soldermask Bottom")
		(17 "Dwgs.User" user "User.Drawings")
		(19 "Cmts.User" user "User.Comments")
		(21 "Eco1.User" user "User.Eco1")
		(23 "Eco2.User" user "User.Eco2")
		(25 "Edge.Cuts" user "Board Geometry/Outline")
		(27 "Margin" user)
		(31 "F.CrtYd" user "Package Geometry/Place Bound Top")
		(29 "B.CrtYd" user "Package Geometry/Place Bound Bottom")
		(35 "F.Fab" user "Ref Des/Assembly Top")
		(33 "B.Fab" user "Ref Des/Assembly Bottom")
	)
	(footprint ""
		(layer "F.Cu")
		(at 430.573688 -362.18368 -90)
		(property "Reference" "PC1173_P0_3"
			(at 0 0 270)
			(layer "F.SilkS")
			(hide yes)
			(effects
				(font
					(size 1.27 1.27)
				)
			)
		)
		(property "Value" ""
			(at 0 0 270)
			(layer "F.Fab")
			(effects
				(font
					(size 1.27 1.27)
				)
			)
		)
		(duplicate_pad_numbers_are_jumpers no)
		(fp_line
			(start -0.7874 0.4064)
			(end -0.7874 -0.4064)
			(stroke
				(width 0.1524)
				(type default)
			)
			(layer "F.SilkS")
		)
		(fp_line
			(start 0.7874 0.4064)
			(end -0.7874 0.4064)
			(stroke
				(width 0.1524)
				(type default)
			)
			(layer "F.SilkS")
		)
		(fp_line
			(start -0.7874 -0.4064)
			(end 0.7874 -0.4064)
			(stroke
				(width 0.1524)
				(type default)
			)
			(layer "F.SilkS")
		)
		(fp_line
			(start 0.7874 -0.4064)
			(end 0.7874 0.4064)
			(stroke
				(width 0.1524)
				(type default)
			)
			(layer "F.SilkS")
		)
		(fp_line
			(start -0.67945 0.3048)
			(end -0.67945 -0.305054)
			(stroke
				(width 0.1)
				(type default)
			)
			(layer "F.Fab")
		)
		(fp_line
			(start -0.12065 0.3048)
			(end -0.67945 0.3048)
			(stroke
				(width 0.1)
				(type default)
			)
			(layer "F.Fab")
		)
		(fp_line
			(start 0.120396 0.3048)
			(end 0.120396 0.2794)
			(stroke
				(width 0.1)
				(type default)
			)
			(layer "F.Fab")
		)
		(fp_line
			(start 0.67945 0.3048)
			(end 0.120396 0.3048)
			(stroke
				(width 0.1)
				(type default)
			)
			(layer "F.Fab")
		)
		(fp_line
			(start -0.12065 0.2794)
			(end -0.12065 0.3048)
			(stroke
				(width 0.1)
				(type default)
			)
			(layer "F.Fab")
		)
		(fp_line
			(start 0.120396 0.2794)
			(end -0.12065 0.2794)
			(stroke
				(width 0.1)
				(type default)
			)
			(layer "F.Fab")
		)
		(fp_line
			(start -0.12065 -0.2794)
			(end 0.12065 -0.2794)
			(stroke
				(width 0.1)
				(type default)
			)
			(layer "F.Fab")
		)
		(fp_line
			(start 0.12065 -0.2794)
			(end 0.12065 -0.3048)
			(stroke
				(width 0.1)
				(type default)
			)
			(layer "F.Fab")
		)
		(fp_line
			(start 0.12065 -0.3048)
			(end 0.67945 -0.3048)
			(stroke
				(width 0.1)
				(type default)
			)
			(layer "F.Fab")
		)
		(fp_line
			(start 0.67945 -0.3048)
			(end 0.67945 0.3048)
			(stroke
				(width 0.1)
				(type default)
			)
			(layer "F.Fab")
		)
		(fp_line
			(start -0.67945 -0.305054)
			(end -0.12065 -0.305054)
			(stroke
				(width 0.1)
				(type default)
			)
			(layer "F.Fab")
		)
		(fp_line
			(start -0.12065 -0.305054)
			(end -0.12065 -0.2794)
			(stroke
				(width 0.1)
				(type default)
			)
			(layer "F.Fab")
		)
		(pad "1" smd circle
			(at -0.40005 0 270)
			(size 0 0)
			(layers "F.Cu" "F.Mask" "F.Paste")
			(net "SW_P12V_PVCCFA_EHV_FIVRA_CPU0_R")
		)
		(pad "2" smd circle
			(at 0.40005 0 270)
			(size 0 0)
			(layers "F.Cu" "F.Mask" "F.Paste")
			(net "GND")
		)
	)
	(footprint ""
		(layer "F.Cu")
		(at 385.716272 -64.672464)
		(property "Reference" "R763"
			(at 0 0 0)
			(layer "F.SilkS")
			(hide yes)
			(effects
				(font
					(size 1.27 1.27)
				)
			)
		)
		(property "Value" ""
			(at 0 0 0)
			(layer "F.Fab")
			(effects
				(font
					(size 1.27 1.27)
				)
			)
		)
		(duplicate_pad_numbers_are_jumpers no)
		(fp_line
			(start -0.7874 -0.4064)
			(end 0.7874 -0.4064)
			(stroke
				(width 0.1524)
				(type default)
			)
			(layer "F.SilkS")
		)
		(fp_line
			(start -0.7874 0.4064)
			(end -0.7874 -0.4064)
			(stroke
				(width 0.1524)
				(type default)
			)
			(layer "F.SilkS")
		)
		(fp_line
			(start 0.7874 -0.4064)
			(end 0.7874 0.4064)
			(stroke
				(width 0.1524)
				(type default)
			)
			(layer "F.SilkS")
		)
		(fp_line
			(start 0.7874 0.4064)
			(end -0.7874 0.4064)
			(stroke
				(width 0.1524)
				(type default)
			)
			(layer "F.SilkS")
		)
		(fp_line
			(start -0.67945 -0.305054)
			(end -0.12065 -0.305054)
			(stroke
				(width 0.1)
				(type default)
			)
			(layer "F.Fab")
		)
		(fp_line
			(start -0.67945 0.3048)
			(end -0.67945 -0.305054)
			(stroke
				(width 0.1)
				(type default)
			)
			(layer "F.Fab")
		)
		(fp_line
			(start -0.12065 -0.305054)
			(end -0.12065 -0.2794)
			(stroke
				(width 0.1)
				(type default)
			)
			(layer "F.Fab")
		)
		(fp_line
			(start -0.12065 -0.2794)
			(end 0.12065 -0.2794)
			(stroke
				(width 0.1)
				(type default)
			)
			(layer "F.Fab")
		)
		(fp_line
			(start -0.12065 0.2794)
			(end -0.12065 0.3048)
			(stroke
				(width 0.1)
				(type default)
			)
			(layer "F.Fab")
		)
		(fp_line
			(start -0.12065 0.3048)
			(end -0.67945 0.3048)
			(stroke
				(width 0.1)
				(type default)
			)
			(layer "F.Fab")
		)
		(fp_line
			(start 0.120396 0.2794)
			(end -0.12065 0.2794)
			(stroke
				(width 0.1)
				(type default)
			)
			(layer "F.Fab")
		)
		(fp_line
			(start 0.120396 0.3048)
			(end 0.120396 0.2794)
			(stroke
				(width 0.1)
				(type default)
			)
			(layer "F.Fab")
		)
		(fp_line
			(start 0.12065 -0.3048)
			(end 0.67945 -0.3048)
			(stroke
				(width 0.1)
				(type default)
			)
			(layer "F.Fab")
		)
		(fp_line
			(start 0.12065 -0.2794)
			(end 0.12065 -0.3048)
			(stroke
				(width 0.1)
				(type default)
			)
			(layer "F.Fab")
		)
		(fp_line
			(start 0.67945 -0.3048)
			(end 0.67945 0.3048)
			(stroke
				(width 0.1)
				(type default)
			)
			(layer "F.Fab")
		)
		(fp_line
			(start 0.67945 0.3048)
			(end 0.120396 0.3048)
			(stroke
				(width 0.1)
				(type default)
			)
			(layer "F.Fab")
		)
		(pad "1" smd circle
			(at -0.40005 0)
			(size 0 0)
			(layers "F.Cu" "F.Mask" "F.Paste")
			(net "JTAG_DBP_TDI")
		)
		(pad "2" smd circle
			(at 0.40005 0)
			(size 0 0)
			(layers "F.Cu" "F.Mask" "F.Paste")
			(net "JTAG_DBP_TDI_R")
		)
	)
	(footprint ""
		(layer "F.Cu")
		(at 303.18456 -435.63667 90)
		(property "Reference" "Q130"
			(at -7.3787 -2.588768 90)
			(unlocked yes)
			(layer "F.SilkS")
			(effects
				(font
					(size 0.7874 0.5842)
					(thickness 0.1524)
				)
				(justify left)
			)
		)
		(property "Value" ""
			(at 0 0 90)
			(layer "F.Fab")
			(effects
				(font
					(size 1.27 1.27)
				)
			)
		)
		(duplicate_pad_numbers_are_jumpers no)
		(fp_line
			(start 1.332738 -1.100074)
			(end 1.332738 1.100074)
			(stroke
				(width 0.1524)
				(type default)
			)
			(layer "F.SilkS")
		)
		(fp_line
			(start 0.4826 -1.100074)
			(end 1.332738 -1.100074)
			(stroke
				(width 0.1524)
				(type default)
			)
			(layer "F.SilkS")
		)
		(fp_line
			(start -0.4826 -1.100074)
			(end 0 -0.541274)
			(stroke
				(width 0.1524)
				(type default)
			)
			(layer "F.SilkS")
		)
		(fp_line
			(start -1.332738 -1.100074)
			(end -0.4826 -1.100074)
			(stroke
				(width 0.1524)
				(type default)
			)
			(layer "F.SilkS")
		)
		(fp_line
			(start 0 -0.541274)
			(end 0.4826 -1.100074)
			(stroke
				(width 0.1524)
				(type default)
			)
			(layer "F.SilkS")
		)
		(fp_line
			(start 1.332738 1.100074)
			(end -1.332738 1.100074)
			(stroke
				(width 0.1524)
				(type default)
			)
			(layer "F.SilkS")
		)
		(fp_line
			(start -1.332738 1.100074)
			(end -1.332738 -1.100074)
			(stroke
				(width 0.1524)
				(type default)
			)
			(layer "F.SilkS")
		)
		(fp_poly
			(pts
				(xy -1.893062 -1.670558) (xy -1.644904 -0.926084) (xy -2.389378 -1.174242)
			)
			(stroke
				(width 0)
				(type default)
			)
			(fill yes)
			(layer "F.SilkS")
		)
		(fp_line
			(start 0.674878 -1.100074)
			(end 0.674878 1.100074)
			(stroke
				(width 0.1)
				(type default)
			)
			(layer "F.Fab")
		)
		(fp_line
			(start -0.674878 -1.100074)
			(end 0.674878 -1.100074)
			(stroke
				(width 0.1)
				(type default)
			)
			(layer "F.Fab")
		)
		(fp_line
			(start 0.674878 1.100074)
			(end -0.674878 1.100074)
			(stroke
				(width 0.1)
				(type default)
			)
			(layer "F.Fab")
		)
		(fp_line
			(start -0.674878 1.100074)
			(end -0.674878 -1.100074)
			(stroke
				(width 0.1)
				(type default)
			)
			(layer "F.Fab")
		)
		(fp_poly
			(pts
				(xy -2.2352 -0.298958) (xy -2.2352 -1.001014) (xy -1.533144 -0.649986)
			)
			(stroke
				(width 0)
				(type default)
			)
			(fill yes)
			(layer "F.Fab")
		)
		(pad "1" smd rect
			(at -0.94996 -0.649986 180)
			(size 0.4318 0.508)
			(layers "F.Cu" "F.Mask" "F.Paste")
			(net "GND")
		)
		(pad "2" smd rect
			(at -0.94996 0 180)
			(size 0.4318 0.508)
			(layers "F.Cu" "F.Mask" "F.Paste")
			(net "GPU_3V3IO_RSVD3_FFU")
		)
		(pad "3" smd rect
			(at -0.94996 0.649986 180)
			(size 0.4318 0.508)
			(layers "F.Cu" "F.Mask" "F.Paste")
			(net "GPU_3V3IO_RSVD3_FFU_ISO")
		)
		(pad "4" smd rect
			(at 0.94996 0.649986 180)
			(size 0.4318 0.508)
			(layers "F.Cu" "F.Mask" "F.Paste")
			(net "GND")
		)
		(pad "5" smd rect
			(at 0.94996 0 180)
			(size 0.4318 0.508)
			(layers "F.Cu" "F.Mask" "F.Paste")
			(net "GPU_3V3IO_RSVD3_FFU_N")
		)
		(pad "6" smd rect
			(at 0.94996 -0.649986 180)
			(size 0.4318 0.508)
			(layers "F.Cu" "F.Mask" "F.Paste")
			(net "GPU_3V3IO_RSVD3_FFU_N")
		)
	)
	(footprint ""
		(layer "F.Cu")
		(at 274.69846 -93.741494 180)
		(property "Reference" "R714"
			(at 0 0 180)
			(layer "F.SilkS")
			(hide yes)
			(effects
				(font
					(size 1.27 1.27)
				)
			)
		)
		(property "Value" ""
			(at 0 0 180)
			(layer "F.Fab")
			(effects
				(font
					(size 1.27 1.27)
				)
			)
		)
		(duplicate_pad_numbers_are_jumpers no)
		(fp_line
			(start 0.7874 0.4064)
			(end -0.7874 0.4064)
			(stroke
				(width 0.1524)
				(type default)
			)
			(layer "F.SilkS")
		)
		(fp_line
			(start 0.7874 -0.4064)
			(end 0.7874 0.4064)
			(stroke
				(width 0.1524)
				(type default)
			)
			(layer "F.SilkS")
		)
		(fp_line
			(start -0.7874 0.4064)
			(end -0.7874 -0.4064)
			(stroke
				(width 0.1524)
				(type default)
			)
			(layer "F.SilkS")
		)
		(fp_line
			(start -0.7874 -0.4064)
			(end 0.7874 -0.4064)
			(stroke
				(width 0.1524)
				(type default)
			)
			(layer "F.SilkS")
		)
		(fp_line
			(start 0.67945 0.3048)
			(end 0.120396 0.3048)
			(stroke
				(width 0.1)
				(type default)
			)
			(layer "F.Fab")
		)
		(fp_line
			(start 0.67945 -0.3048)
			(end 0.67945 0.3048)
			(stroke
				(width 0.1)
				(type default)
			)
			(layer "F.Fab")
		)
		(fp_line
			(start 0.12065 -0.2794)
			(end 0.12065 -0.3048)
			(stroke
				(width 0.1)
				(type default)
			)
			(layer "F.Fab")
		)
		(fp_line
			(start 0.12065 -0.3048)
			(end 0.67945 -0.3048)
			(stroke
				(width 0.1)
				(type default)
			)
			(layer "F.Fab")
		)
		(fp_line
			(start 0.120396 0.3048)
			(end 0.120396 0.2794)
			(stroke
				(width 0.1)
				(type default)
			)
			(layer "F.Fab")
		)
		(fp_line
			(start 0.120396 0.2794)
			(end -0.12065 0.2794)
			(stroke
				(width 0.1)
				(type default)
			)
			(layer "F.Fab")
		)
		(fp_line
			(start -0.12065 0.3048)
			(end -0.67945 0.3048)
			(stroke
				(width 0.1)
				(type default)
			)
			(layer "F.Fab")
		)
		(fp_line
			(start -0.12065 0.2794)
			(end -0.12065 0.3048)
			(stroke
				(width 0.1)
				(type default)
			)
			(layer "F.Fab")
		)
		(fp_line
			(start -0.12065 -0.2794)
			(end 0.12065 -0.2794)
			(stroke
				(width 0.1)
				(type default)
			)
			(layer "F.Fab")
		)
		(fp_line
			(start -0.12065 -0.305054)
			(end -0.12065 -0.2794)
			(stroke
				(width 0.1)
				(type default)
			)
			(layer "F.Fab")
		)
		(fp_line
			(start -0.67945 0.3048)
			(end -0.67945 -0.305054)
			(stroke
				(width 0.1)
				(type default)
			)
			(layer "F.Fab")
		)
		(fp_line
			(start -0.67945 -0.305054)
			(end -0.12065 -0.305054)
			(stroke
				(width 0.1)
				(type default)
			)
			(layer "F.Fab")
		)
		(pad "1" smd circle
			(at -0.40005 0 180)
			(size 0 0)
			(layers "F.Cu" "F.Mask" "F.Paste")
			(net "MB_FRU_ADDR2")
		)
		(pad "2" smd circle
			(at 0.40005 0 180)
			(size 0 0)
			(layers "F.Cu" "F.Mask" "F.Paste")
			(net "GND")
		)
	)
	(footprint ""
		(layer "F.Cu")
		(at 285.689548 -413.23514 90)
		(property "Reference" "R4552"
			(at 0 0 90)
			(layer "F.SilkS")
			(hide yes)
			(effects
				(font
					(size 1.27 1.27)
				)
			)
		)
		(property "Value" ""
			(at 0 0 90)
			(layer "F.Fab")
			(effects
				(font
					(size 1.27 1.27)
				)
			)
		)
		(duplicate_pad_numbers_are_jumpers no)
		(fp_line
			(start 0.7874 -0.4064)
			(end 0.7874 0.4064)
			(stroke
				(width 0.1524)
				(type default)
			)
			(layer "F.SilkS")
		)
		(fp_line
			(start -0.7874 -0.4064)
			(end 0.7874 -0.4064)
			(stroke
				(width 0.1524)
				(type default)
			)
			(layer "F.SilkS")
		)
		(fp_line
			(start 0.7874 0.4064)
			(end -0.7874 0.4064)
			(stroke
				(width 0.1524)
				(type default)
			)
			(layer "F.SilkS")
		)
		(fp_line
			(start -0.7874 0.4064)
			(end -0.7874 -0.4064)
			(stroke
				(width 0.1524)
				(type default)
			)
			(layer "F.SilkS")
		)
		(fp_line
			(start -0.12065 -0.305054)
			(end -0.12065 -0.2794)
			(stroke
				(width 0.1)
				(type default)
			)
			(layer "F.Fab")
		)
		(fp_line
			(start -0.67945 -0.305054)
			(end -0.12065 -0.305054)
			(stroke
				(width 0.1)
				(type default)
			)
			(layer "F.Fab")
		)
		(fp_line
			(start 0.67945 -0.3048)
			(end 0.67945 0.3048)
			(stroke
				(width 0.1)
				(type default)
			)
			(layer "F.Fab")
		)
		(fp_line
			(start 0.12065 -0.3048)
			(end 0.67945 -0.3048)
			(stroke
				(width 0.1)
				(type default)
			)
			(layer "F.Fab")
		)
		(fp_line
			(start 0.12065 -0.2794)
			(end 0.12065 -0.3048)
			(stroke
				(width 0.1)
				(type default)
			)
			(layer "F.Fab")
		)
		(fp_line
			(start -0.12065 -0.2794)
			(end 0.12065 -0.2794)
			(stroke
				(width 0.1)
				(type default)
			)
			(layer "F.Fab")
		)
		(fp_line
			(start 0.120396 0.2794)
			(end -0.12065 0.2794)
			(stroke
				(width 0.1)
				(type default)
			)
			(layer "F.Fab")
		)
		(fp_line
			(start -0.12065 0.2794)
			(end -0.12065 0.3048)
			(stroke
				(width 0.1)
				(type default)
			)
			(layer "F.Fab")
		)
		(fp_line
			(start 0.67945 0.3048)
			(end 0.120396 0.3048)
			(stroke
				(width 0.1)
				(type default)
			)
			(layer "F.Fab")
		)
		(fp_line
			(start 0.120396 0.3048)
			(end 0.120396 0.2794)
			(stroke
				(width 0.1)
				(type default)
			)
			(layer "F.Fab")
		)
		(fp_line
			(start -0.12065 0.3048)
			(end -0.67945 0.3048)
			(stroke
				(width 0.1)
				(type default)
			)
			(layer "F.Fab")
		)
		(fp_line
			(start -0.67945 0.3048)
			(end -0.67945 -0.305054)
			(stroke
				(width 0.1)
				(type default)
			)
			(layer "F.Fab")
		)
		(pad "1" smd circle
			(at -0.40005 0 90)
			(size 0 0)
			(layers "F.Cu" "F.Mask" "F.Paste")
			(net "HPDB_HSC_PWRGD")
		)
		(pad "2" smd circle
			(at 0.40005 0 90)
			(size 0 0)
			(layers "F.Cu" "F.Mask" "F.Paste")
			(net "GND")
		)
	)
	(footprint ""
		(layer "F.Cu")
		(at 142.42288 -40.985948)
		(property "Reference" "R2113"
			(at 0 0 0)
			(layer "F.SilkS")
			(hide yes)
			(effects
				(font
					(size 1.27 1.27)
				)
			)
		)
		(property "Value" ""
			(at 0 0 0)
			(layer "F.Fab")
			(effects
				(font
					(size 1.27 1.27)
				)
			)
		)
		(duplicate_pad_numbers_are_jumpers no)
		(fp_line
			(start -0.7874 -0.4064)
			(end 0.7874 -0.4064)
			(stroke
				(width 0.1524)
				(type default)
			)
			(layer "F.SilkS")
		)
		(fp_line
			(start -0.7874 0.4064)
			(end -0.7874 -0.4064)
			(stroke
				(width 0.1524)
				(type default)
			)
			(layer "F.SilkS")
		)
		(fp_line
			(start 0.7874 -0.4064)
			(end 0.7874 0.4064)
			(stroke
				(width 0.1524)
				(type default)
			)
			(layer "F.SilkS")
		)
		(fp_line
			(start 0.7874 0.4064)
			(end -0.7874 0.4064)
			(stroke
				(width 0.1524)
				(type default)
			)
			(layer "F.SilkS")
		)
		(fp_line
			(start -0.67945 -0.305054)
			(end -0.12065 -0.305054)
			(stroke
				(width 0.1)
				(type default)
			)
			(layer "F.Fab")
		)
		(fp_line
			(start -0.67945 0.3048)
			(end -0.67945 -0.305054)
			(stroke
				(width 0.1)
				(type default)
			)
			(layer "F.Fab")
		)
		(fp_line
			(start -0.12065 -0.305054)
			(end -0.12065 -0.2794)
			(stroke
				(width 0.1)
				(type default)
			)
			(layer "F.Fab")
		)
		(fp_line
			(start -0.12065 -0.2794)
			(end 0.12065 -0.2794)
			(stroke
				(width 0.1)
				(type default)
			)
			(layer "F.Fab")
		)
		(fp_line
			(start -0.12065 0.2794)
			(end -0.12065 0.3048)
			(stroke
				(width 0.1)
				(type default)
			)
			(layer "F.Fab")
		)
		(fp_line
			(start -0.12065 0.3048)
			(end -0.67945 0.3048)
			(stroke
				(width 0.1)
				(type default)
			)
			(layer "F.Fab")
		)
		(fp_line
			(start 0.120396 0.2794)
			(end -0.12065 0.2794)
			(stroke
				(width 0.1)
				(type default)
			)
			(layer "F.Fab")
		)
		(fp_line
			(start 0.120396 0.3048)
			(end 0.120396 0.2794)
			(stroke
				(width 0.1)
				(type default)
			)
			(layer "F.Fab")
		)
		(fp_line
			(start 0.12065 -0.3048)
			(end 0.67945 -0.3048)
			(stroke
				(width 0.1)
				(type default)
			)
			(layer "F.Fab")
		)
		(fp_line
			(start 0.12065 -0.2794)
			(end 0.12065 -0.3048)
			(stroke
				(width 0.1)
				(type default)
			)
			(layer "F.Fab")
		)
		(fp_line
			(start 0.67945 -0.3048)
			(end 0.67945 0.3048)
			(stroke
				(width 0.1)
				(type default)
			)
			(layer "F.Fab")
		)
		(fp_line
			(start 0.67945 0.3048)
			(end 0.120396 0.3048)
			(stroke
				(width 0.1)
				(type default)
			)
			(layer "F.Fab")
		)
		(pad "1" smd circle
			(at -0.40005 0)
			(size 0 0)
			(layers "F.Cu" "F.Mask" "F.Paste")
			(net "RST_PCIE_PCH_DEV_BUF_M2_0_PERST")
		)
		(pad "2" smd circle
			(at 0.40005 0)
			(size 0 0)
			(layers "F.Cu" "F.Mask" "F.Paste")
			(net "RST_PCIE_PCH_DEV_0_N")
		)
	)
)
